(kicad_pcb
	(version 20241229)
	(generator "pcbnew")
	(generator_version "9.0")
	(general
		(thickness 1.61)
		(legacy_teardrops no)
	)
	(paper "A3")
	(title_block
		(title "SO-DIMM DDR5 Tester")
		(date "2025-11-26")
		(rev "1.3.0")
		(comment 9 "footprints 291-296 of 627")
	)
	(layers
		(0 "F.Cu" signal)
		(4 "In1.Cu" power)
		(6 "In2.Cu" mixed)
		(8 "In3.Cu" power)
		(10 "In4.Cu" mixed)
		(12 "In5.Cu" power)
		(14 "In6.Cu" mixed)
		(16 "In7.Cu" power)
		(18 "In8.Cu" power)
		(20 "In9.Cu" mixed)
		(22 "In10.Cu" power)
		(2 "B.Cu" signal)
		(9 "F.Adhes" user "F.Adhesive")
		(11 "B.Adhes" user "B.Adhesive")
		(13 "F.Paste" user)
		(15 "B.Paste" user)
		(5 "F.SilkS" user "F.Silkscreen")
		(7 "B.SilkS" user "B.Silkscreen")
		(1 "F.Mask" user)
		(3 "B.Mask" user)
		(17 "Dwgs.User" user "User.Drawings")
		(19 "Cmts.User" user "User.Comments")
		(21 "Eco1.User" user "User.Eco1")
		(23 "Eco2.User" user "User.Eco2")
		(25 "Edge.Cuts" user)
		(27 "Margin" user)
		(31 "F.CrtYd" user "F.Courtyard")
		(29 "B.CrtYd" user "B.Courtyard")
		(35 "F.Fab" user)
		(33 "B.Fab" user)
	)
	(footprint "antmicro-footprints:R_0402_1005Metric"
		(layer "F.Cu")
		(at 91 181.715 90)
		(descr "Resistor SMD 0402")
		(tags "resistor SMD 0402")
		(property "Reference" "R51"
			(at -1.122484 -0.772697 90)
			(layer "F.SilkS")
			(hide yes)
			(effects
				(font
					(size 0.7 0.7)
					(thickness 0.15)
				)
				(justify left bottom)
			)
		)
		(property "Value" "R_47k_0402"
			(at -1.011843 1.772047 90)
			(layer "F.Fab")
			(effects
				(font
					(size 0.7 0.7)
					(thickness 0.15)
				)
				(justify left bottom)
			)
		)
		(property "Datasheet" "https://www.bourns.com/docs/product-datasheets/cr.pdf"
			(at 0 0 90)
			(layer "F.Fab")
			(hide yes)
			(effects
				(font
					(size 1.27 1.27)
					(thickness 0.15)
				)
			)
		)
		(property "Author" "Antmicro"
			(at 272.715 90.715 0)
			(layer "F.Fab")
			(hide yes)
			(effects
				(font
					(size 1 1)
					(thickness 0.15)
				)
			)
		)
		(property "License" "Apache-2.0"
			(at 272.715 90.715 0)
			(layer "F.Fab")
			(hide yes)
			(effects
				(font
					(size 1 1)
					(thickness 0.15)
				)
			)
		)
		(property "MPN" "CR0402-FX-4702GLF"
			(at 272.715 90.715 0)
			(layer "F.Fab")
			(hide yes)
			(effects
				(font
					(size 1 1)
					(thickness 0.15)
				)
			)
		)
		(property "Manufacturer" "Bourns"
			(at 272.715 90.715 0)
			(layer "F.Fab")
			(hide yes)
			(effects
				(font
					(size 1 1)
					(thickness 0.15)
				)
			)
		)
		(property "Tolerance" "1%"
			(at 272.715 90.715 0)
			(layer "F.Fab")
			(hide yes)
			(effects
				(font
					(size 1 1)
					(thickness 0.15)
				)
			)
		)
		(property "Val" "47k"
			(at 272.715 90.715 0)
			(layer "F.Fab")
			(hide yes)
			(effects
				(font
					(size 1 1)
					(thickness 0.15)
				)
			)
		)
		(sheetname "/Debug FTDI/")
		(sheetfile "debug-ftdi.kicad_sch")
		(attr smd)
		(fp_rect
			(start -0.93 -0.47)
			(end 0.93 0.47)
			(stroke
				(width 0.05)
				(type solid)
			)
			(fill no)
			(layer "F.CrtYd")
		)
		(fp_rect
			(start -0.5 -0.25)
			(end 0.5 0.25)
			(stroke
				(width 0.15)
				(type solid)
			)
			(fill no)
			(layer "F.Fab")
		)
		(pad "1" smd roundrect
			(at -0.485 0 90)
			(size 0.59 0.64)
			(layers "F.Cu" "F.Mask" "F.Paste")
			(roundrect_rratio 0.25)
			(net 263 "FTDI_DIS")
			(pintype "passive")
		)
		(pad "2" smd roundrect
			(at 0.485 0 90)
			(size 0.59 0.64)
			(layers "F.Cu" "F.Mask" "F.Paste")
			(roundrect_rratio 0.25)
			(net 200 "+3V3")
			(pintype "passive")
		)
	)
	(footprint "antmicro-footprints:C_0402_1005Metric"
		(layer "F.Cu")
		(at 121.5 205 180)
		(descr "Capacitor SMD 0402")
		(tags "capacitor SMD 0402")
		(property "Reference" "C176"
			(at 0 -0.699 180)
			(layer "F.SilkS")
			(hide yes)
			(effects
				(font
					(size 0.7 0.7)
					(thickness 0.15)
				)
				(justify left bottom)
			)
		)
		(property "Value" "C_100n_0402"
			(at -1.022927 2.155213 180)
			(layer "F.Fab")
			(effects
				(font
					(size 0.7 0.7)
					(thickness 0.15)
				)
				(justify left bottom)
			)
		)
		(property "Datasheet" "https://www.murata.com/products/productdetail?partno=GRM155R61H104KE14%23"
			(at 0 0 180)
			(layer "F.Fab")
			(hide yes)
			(effects
				(font
					(size 1.27 1.27)
					(thickness 0.15)
				)
			)
		)
		(property "Author" "Antmicro"
			(at 243 410 0)
			(layer "F.Fab")
			(hide yes)
			(effects
				(font
					(size 1 1)
					(thickness 0.15)
				)
			)
		)
		(property "Dielectric" "X5R"
			(at 243 410 0)
			(layer "F.Fab")
			(hide yes)
			(effects
				(font
					(size 1 1)
					(thickness 0.15)
				)
			)
		)
		(property "License" "Apache-2.0"
			(at 243 410 0)
			(layer "F.Fab")
			(hide yes)
			(effects
				(font
					(size 1 1)
					(thickness 0.15)
				)
			)
		)
		(property "MPN" "GRM155R61H104KE14D"
			(at 243 410 0)
			(layer "F.Fab")
			(hide yes)
			(effects
				(font
					(size 1 1)
					(thickness 0.15)
				)
			)
		)
		(property "Manufacturer" "Murata"
			(at 243 410 0)
			(layer "F.Fab")
			(hide yes)
			(effects
				(font
					(size 1 1)
					(thickness 0.15)
				)
			)
		)
		(property "Val" "100n"
			(at 243 410 0)
			(layer "F.Fab")
			(hide yes)
			(effects
				(font
					(size 1 1)
					(thickness 0.15)
				)
			)
		)
		(property "Voltage" "50V"
			(at 243 410 0)
			(layer "F.Fab")
			(hide yes)
			(effects
				(font
					(size 1 1)
					(thickness 0.15)
				)
			)
		)
		(sheetname "/Supply/")
		(sheetfile "supply.kicad_sch")
		(attr smd)
		(fp_rect
			(start -0.9659 -0.481258)
			(end 0.9649 0.458742)
			(stroke
				(width 0.05)
				(type solid)
			)
			(fill no)
			(layer "F.CrtYd")
		)
		(fp_line
			(start 0.499 0.248)
			(end -0.499 0.248)
			(stroke
				(width 0.15)
				(type solid)
			)
			(layer "F.Fab")
		)
		(fp_line
			(start 0.499 -0.25)
			(end 0.499 0.248)
			(stroke
				(width 0.15)
				(type solid)
			)
			(layer "F.Fab")
		)
		(fp_line
			(start -0.499 0.248)
			(end -0.499 -0.25)
			(stroke
				(width 0.15)
				(type solid)
			)
			(layer "F.Fab")
		)
		(fp_line
			(start -0.499 -0.25)
			(end 0.499 -0.25)
			(stroke
				(width 0.15)
				(type solid)
			)
			(layer "F.Fab")
		)
		(pad "1" smd roundrect
			(at -0.484 0 180)
			(size 0.59 0.64)
			(layers "F.Cu" "F.Mask" "F.Paste")
			(roundrect_rratio 0.25)
			(net 1 "GND")
			(pintype "passive")
		)
		(pad "2" smd roundrect
			(at 0.484 0 180)
			(size 0.59 0.64)
			(layers "F.Cu" "F.Mask" "F.Paste")
			(roundrect_rratio 0.25)
			(net 596 "/Supply/12V_PCIE_fused")
			(pintype "passive")
		)
	)
	(footprint "antmicro-footprints:SOT-23-6"
		(layer "F.Cu")
		(at 184.391759 133.2071 180)
		(property "Reference" "U17"
			(at 1.765759 -0.1429 270)
			(layer "F.SilkS")
			(effects
				(font
					(size 0.7 0.7)
					(thickness 0.15)
				)
				(justify left bottom)
			)
		)
		(property "Value" "LTC4412IS6"
			(at -1.75 2.75 180)
			(layer "F.Fab")
			(effects
				(font
					(size 0.7 0.7)
					(thickness 0.15)
				)
				(justify left bottom)
			)
		)
		(property "Datasheet" "https://www.mouser.com/datasheet/2/308/NCV8187_D-1813214.pdf"
			(at 0 0 180)
			(layer "F.Fab")
			(hide yes)
			(effects
				(font
					(size 1.27 1.27)
					(thickness 0.15)
				)
			)
		)
		(property "Author" "Antmicro"
			(at 368.783518 266.4142 0)
			(layer "F.Fab")
			(hide yes)
			(effects
				(font
					(size 1 1)
					(thickness 0.15)
				)
			)
		)
		(property "License" "Apache-2.0"
			(at 368.783518 266.4142 0)
			(layer "F.Fab")
			(hide yes)
			(effects
				(font
					(size 1 1)
					(thickness 0.15)
				)
			)
		)
		(property "MPN" "LTC4412IS6#TRMPBF"
			(at 368.783518 266.4142 0)
			(layer "F.Fab")
			(hide yes)
			(effects
				(font
					(size 1 1)
					(thickness 0.15)
				)
			)
		)
		(property "Manufacturer" "Analog Devices"
			(at 368.783518 266.4142 0)
			(layer "F.Fab")
			(hide yes)
			(effects
				(font
					(size 1 1)
					(thickness 0.15)
				)
			)
		)
		(sheetname "/Supply/")
		(sheetfile "supply.kicad_sch")
		(attr smd)
		(fp_line
			(start 1.45 0.7)
			(end 1.45 0.4)
			(stroke
				(width 0.12)
				(type solid)
			)
			(layer "F.SilkS")
		)
		(fp_line
			(start 1.45 -0.7)
			(end 1.45 -0.4)
			(stroke
				(width 0.12)
				(type solid)
			)
			(layer "F.SilkS")
		)
		(fp_line
			(start 1.3 0.7)
			(end 1.45 0.7)
			(stroke
				(width 0.12)
				(type solid)
			)
			(layer "F.SilkS")
		)
		(fp_line
			(start 1.3 -0.7)
			(end 1.45 -0.7)
			(stroke
				(width 0.12)
				(type solid)
			)
			(layer "F.SilkS")
		)
		(fp_line
			(start -1.3 -0.7)
			(end -1.45 -0.7)
			(stroke
				(width 0.12)
				(type solid)
			)
			(layer "F.SilkS")
		)
		(fp_line
			(start -1.45 0.7)
			(end -1.45 0.4)
			(stroke
				(width 0.12)
				(type solid)
			)
			(layer "F.SilkS")
		)
		(fp_line
			(start -1.45 -0.7)
			(end -1.45 -0.4)
			(stroke
				(width 0.12)
				(type solid)
			)
			(layer "F.SilkS")
		)
		(fp_rect
			(start -1.55 -1.85)
			(end 1.55 1.75)
			(stroke
				(width 0.05)
				(type solid)
			)
			(fill no)
			(layer "F.CrtYd")
		)
		(fp_line
			(start 1.5 0.7)
			(end -1.5 0.7)
			(stroke
				(width 0.1)
				(type solid)
			)
			(layer "F.Fab")
		)
		(fp_line
			(start 1.5 -0.7)
			(end 1.5 0.7)
			(stroke
				(width 0.1)
				(type solid)
			)
			(layer "F.Fab")
		)
		(fp_line
			(start -1.5 0.7)
			(end -1.5 -0.7)
			(stroke
				(width 0.1)
				(type solid)
			)
			(layer "F.Fab")
		)
		(fp_line
			(start -1.5 -0.7)
			(end 1.5 -0.7)
			(stroke
				(width 0.1)
				(type solid)
			)
			(layer "F.Fab")
		)
		(fp_text user "."
			(at -1.4 1.2 0)
			(layer "F.SilkS")
			(effects
				(font
					(size 1 1)
					(thickness 0.15)
				)
			)
		)
		(pad "1" smd roundrect
			(at -0.954 1.1 180)
			(size 0.55 1)
			(layers "F.Cu" "F.Mask" "F.Paste")
			(roundrect_rratio 0.15)
			(net 595 "/Supply/12V_aux_fused")
			(pinfunction "IN")
			(pintype "power_in")
		)
		(pad "2" smd roundrect
			(at -0.003 1.1 180)
			(size 0.55 1)
			(layers "F.Cu" "F.Mask" "F.Paste")
			(roundrect_rratio 0.15)
			(net 1 "GND")
			(pinfunction "GND")
			(pintype "power_in")
		)
		(pad "3" smd roundrect
			(at 0.947 1.1 180)
			(size 0.55 1)
			(layers "F.Cu" "F.Mask" "F.Paste")
			(roundrect_rratio 0.15)
			(net 1 "GND")
			(pinfunction "CTL")
			(pintype "input")
		)
		(pad "4" smd roundrect
			(at 0.947 -1.214 180)
			(size 0.55 1)
			(layers "F.Cu" "F.Mask" "F.Paste")
			(roundrect_rratio 0.15)
			(net 724 "unconnected-(U17-STAT-Pad4)")
			(pinfunction "STAT")
			(pintype "output+no_connect")
		)
		(pad "5" smd roundrect
			(at -0.003 -1.214 180)
			(size 0.55 1)
			(layers "F.Cu" "F.Mask" "F.Paste")
			(roundrect_rratio 0.15)
			(net 365 "Net-(Q12-G)")
			(pinfunction "GATE")
			(pintype "output")
		)
		(pad "6" smd roundrect
			(at -0.954 -1.214 180)
			(size 0.55 1)
			(layers "F.Cu" "F.Mask" "F.Paste")
			(roundrect_rratio 0.15)
			(net 38 "VDC")
			(pinfunction "SENSE")
			(pintype "input")
		)
	)
	(footprint "antmicro-footprints:C_0603_1608Metric"
		(layer "F.Cu")
		(at 184.491759 135.907099)
		(descr "Capacitor SMD 0603")
		(tags "capacitor 0603")
		(property "Reference" "C179"
			(at -1.42757 -1.000252 0)
			(layer "F.SilkS")
			(hide yes)
			(effects
				(font
					(size 0.7 0.7)
					(thickness 0.15)
				)
				(justify left bottom)
			)
		)
		(property "Value" "C_1u_25V_0603"
			(at -1.42757 1.770288 0)
			(layer "F.Fab")
			(effects
				(font
					(size 0.7 0.7)
					(thickness 0.15)
				)
				(justify left bottom)
			)
		)
		(property "Datasheet" "https://product.samsungsem.com/mlcc/CL10A105KA8NNN.do"
			(at 0 0 0)
			(layer "F.Fab")
			(hide yes)
			(effects
				(font
					(size 1.27 1.27)
					(thickness 0.15)
				)
			)
		)
		(property "Author" "Antmicro"
			(at 0 0 0)
			(layer "F.Fab")
			(hide yes)
			(effects
				(font
					(size 1 1)
					(thickness 0.15)
				)
			)
		)
		(property "Dielectric" ""
			(at 0 0 0)
			(layer "F.Fab")
			(hide yes)
			(effects
				(font
					(size 1 1)
					(thickness 0.15)
				)
			)
		)
		(property "License" "Apache-2.0"
			(at 0 0 0)
			(layer "F.Fab")
			(hide yes)
			(effects
				(font
					(size 1 1)
					(thickness 0.15)
				)
			)
		)
		(property "MPN" "CL10A105KA8NNNC"
			(at 0 0 0)
			(layer "F.Fab")
			(hide yes)
			(effects
				(font
					(size 1 1)
					(thickness 0.15)
				)
			)
		)
		(property "Manufacturer" "Samsung Electro-Mechanics"
			(at 0 0 0)
			(layer "F.Fab")
			(hide yes)
			(effects
				(font
					(size 1 1)
					(thickness 0.15)
				)
			)
		)
		(property "Val" "1u/25V"
			(at 0 0 0)
			(layer "F.Fab")
			(hide yes)
			(effects
				(font
					(size 1 1)
					(thickness 0.15)
				)
			)
		)
		(property "Voltage" ""
			(at 0 0 0)
			(layer "F.Fab")
			(hide yes)
			(effects
				(font
					(size 1 1)
					(thickness 0.15)
				)
			)
		)
		(sheetname "/Supply/")
		(sheetfile "supply.kicad_sch")
		(attr smd)
		(fp_line
			(start -0.3 -0.3)
			(end 0.3 -0.3)
			(stroke
				(width 0.15)
				(type solid)
			)
			(layer "F.SilkS")
		)
		(fp_line
			(start -0.3 0.3)
			(end 0.3 0.3)
			(stroke
				(width 0.15)
				(type solid)
			)
			(layer "F.SilkS")
		)
		(fp_rect
			(start -1.24 -0.7)
			(end 1.24 0.7)
			(stroke
				(width 0.05)
				(type solid)
			)
			(fill no)
			(layer "F.CrtYd")
		)
		(fp_rect
			(start -0.8 -0.4)
			(end 0.8 0.4)
			(stroke
				(width 0.15)
				(type solid)
			)
			(fill no)
			(layer "F.Fab")
		)
		(pad "1" smd roundrect
			(at -0.7 0)
			(size 0.6 0.8)
			(layers "F.Cu" "F.Mask" "F.Paste")
			(roundrect_rratio 0.2)
			(net 1 "GND")
			(pintype "passive")
		)
		(pad "2" smd roundrect
			(at 0.7 0)
			(size 0.6 0.8)
			(layers "F.Cu" "F.Mask" "F.Paste")
			(roundrect_rratio 0.2)
			(net 38 "VDC")
			(pintype "passive")
		)
	)
	(footprint "antmicro-footprints:C_0805_2012Metric"
		(layer "F.Cu")
		(at 205.281001 166.922 90)
		(descr "Capacitor SMD 0805")
		(tags "capacitor SMD 0805")
		(property "Reference" "C173"
			(at -2.10551 -1.198678 90)
			(layer "F.SilkS")
			(hide yes)
			(effects
				(font
					(size 0.7 0.7)
					(thickness 0.15)
				)
				(justify left bottom)
			)
		)
		(property "Value" "C_22u_25V_0805"
			(at -2.055717 1.963152 90)
			(layer "F.Fab")
			(effects
				(font
					(size 0.7 0.7)
					(thickness 0.15)
				)
				(justify left bottom)
			)
		)
		(property "Datasheet" "https://product.samsungsem.com/mlcc/CL21A226MAYNNN.do"
			(at 0 0 90)
			(layer "F.Fab")
			(hide yes)
			(effects
				(font
					(size 1.27 1.27)
					(thickness 0.15)
				)
			)
		)
		(property "Author" "Antmicro"
			(at 372.203001 -38.359001 0)
			(layer "F.Fab")
			(hide yes)
			(effects
				(font
					(size 1 1)
					(thickness 0.15)
				)
			)
		)
		(property "Dielectric" ""
			(at 372.203001 -38.359001 0)
			(layer "F.Fab")
			(hide yes)
			(effects
				(font
					(size 1 1)
					(thickness 0.15)
				)
			)
		)
		(property "License" "Apache-2.0"
			(at 372.203001 -38.359001 0)
			(layer "F.Fab")
			(hide yes)
			(effects
				(font
					(size 1 1)
					(thickness 0.15)
				)
			)
		)
		(property "MPN" "CL21A226MAYNNNE"
			(at 372.203001 -38.359001 0)
			(layer "F.Fab")
			(hide yes)
			(effects
				(font
					(size 1 1)
					(thickness 0.15)
				)
			)
		)
		(property "Manufacturer" "Samsung Electro-Mechanics"
			(at 372.203001 -38.359001 0)
			(layer "F.Fab")
			(hide yes)
			(effects
				(font
					(size 1 1)
					(thickness 0.15)
				)
			)
		)
		(property "Val" "22u_25V"
			(at 372.203001 -38.359001 0)
			(layer "F.Fab")
			(hide yes)
			(effects
				(font
					(size 1 1)
					(thickness 0.15)
				)
			)
		)
		(property "Voltage" ""
			(at 372.203001 -38.359001 0)
			(layer "F.Fab")
			(hide yes)
			(effects
				(font
					(size 1 1)
					(thickness 0.15)
				)
			)
		)
		(sheetname "/Supply/")
		(sheetfile "supply.kicad_sch")
		(attr smd)
		(fp_line
			(start -0.3 -0.8)
			(end 0.3 -0.8)
			(stroke
				(width 0.15)
				(type solid)
			)
			(layer "F.SilkS")
		)
		(fp_line
			(start -0.3 0.8)
			(end 0.3 0.8)
			(stroke
				(width 0.15)
				(type solid)
			)
			(layer "F.SilkS")
		)
		(fp_rect
			(start -1.9 -0.93)
			(end 1.9 0.93)
			(stroke
				(width 0.05)
				(type solid)
			)
			(fill no)
			(layer "F.CrtYd")
		)
		(fp_rect
			(start -0.95 -0.675)
			(end 0.95 0.675)
			(stroke
				(width 0.15)
				(type solid)
			)
			(fill no)
			(layer "F.Fab")
		)
		(pad "1" smd rect
			(at -1.05 0 90)
			(size 1.2 1.2)
			(layers "F.Cu" "F.Mask" "F.Paste")
			(net 1 "GND")
			(pintype "passive")
		)
		(pad "2" smd rect
			(at 1.05 0 90)
			(size 1.2 1.2)
			(layers "F.Cu" "F.Mask" "F.Paste")
			(net 38 "VDC")
			(pintype "passive")
		)
	)
	(footprint "antmicro-footprints:C_0603_1608Metric"
		(layer "F.Cu")
		(at 168.655502 195.614502 180)
		(descr "Capacitor SMD 0603")
		(tags "capacitor 0603")
		(property "Reference" "C217"
			(at -1.42757 -1.000252 180)
			(layer "F.SilkS")
			(hide yes)
			(effects
				(font
					(size 0.7 0.7)
					(thickness 0.15)
				)
				(justify left bottom)
			)
		)
		(property "Value" "C_22u_0603"
			(at -1.42757 1.770288 180)
			(layer "F.Fab")
			(effects
				(font
					(size 0.7 0.7)
					(thickness 0.15)
				)
				(justify left bottom)
			)
		)
		(property "Datasheet" "https://www.murata.com/products/productdetail?partno=GRM188R60J226MEA0%23"
			(at 0 0 180)
			(layer "F.Fab")
			(hide yes)
			(effects
				(font
					(size 1.27 1.27)
					(thickness 0.15)
				)
			)
		)
		(property "Author" "Antmicro"
			(at 337.311004 391.229004 0)
			(layer "F.Fab")
			(hide yes)
			(effects
				(font
					(size 1 1)
					(thickness 0.15)
				)
			)
		)
		(property "Dielectric" ""
			(at 337.311004 391.229004 0)
			(layer "F.Fab")
			(hide yes)
			(effects
				(font
					(size 1 1)
					(thickness 0.15)
				)
			)
		)
		(property "License" "Apache-2.0"
			(at 337.311004 391.229004 0)
			(layer "F.Fab")
			(hide yes)
			(effects
				(font
					(size 1 1)
					(thickness 0.15)
				)
			)
		)
		(property "MPN" "GRM188R60J226MEA0D"
			(at 337.311004 391.229004 0)
			(layer "F.Fab")
			(hide yes)
			(effects
				(font
					(size 1 1)
					(thickness 0.15)
				)
			)
		)
		(property "Manufacturer" "Murata"
			(at 337.311004 391.229004 0)
			(layer "F.Fab")
			(hide yes)
			(effects
				(font
					(size 1 1)
					(thickness 0.15)
				)
			)
		)
		(property "Val" "22u"
			(at 337.311004 391.229004 0)
			(layer "F.Fab")
			(hide yes)
			(effects
				(font
					(size 1 1)
					(thickness 0.15)
				)
			)
		)
		(property "Voltage" ""
			(at 337.311004 391.229004 0)
			(layer "F.Fab")
			(hide yes)
			(effects
				(font
					(size 1 1)
					(thickness 0.15)
				)
			)
		)
		(sheetname "/Supply/")
		(sheetfile "supply.kicad_sch")
		(attr smd)
		(fp_line
			(start -0.3 0.3)
			(end 0.3 0.3)
			(stroke
				(width 0.15)
				(type solid)
			)
			(layer "F.SilkS")
		)
		(fp_line
			(start -0.3 -0.3)
			(end 0.3 -0.3)
			(stroke
				(width 0.15)
				(type solid)
			)
			(layer "F.SilkS")
		)
		(fp_rect
			(start -1.24 -0.7)
			(end 1.24 0.7)
			(stroke
				(width 0.05)
				(type solid)
			)
			(fill no)
			(layer "F.CrtYd")
		)
		(fp_rect
			(start -0.8 -0.4)
			(end 0.8 0.4)
			(stroke
				(width 0.15)
				(type solid)
			)
			(fill no)
			(layer "F.Fab")
		)
		(pad "1" smd roundrect
			(at -0.7 0 180)
			(size 0.6 0.8)
			(layers "F.Cu" "F.Mask" "F.Paste")
			(roundrect_rratio 0.2)
			(net 1 "GND")
			(pintype "passive")
		)
		(pad "2" smd roundrect
			(at 0.7 0 180)
			(size 0.6 0.8)
			(layers "F.Cu" "F.Mask" "F.Paste")
			(roundrect_rratio 0.2)
			(net 78 "/Supply/1V0_REG")
			(pintype "passive")
		)
	)
)
